(kicad_pcb
	(version 20260206)
	(generator "pcbnew")
	(generator_version "10.0")
	(general
		(thickness 1.6)
		(legacy_teardrops no)
	)
	(paper "A4")
	(title_block
		(title "Bryce Canyon_SCC_16316-1_OCP.brd")
		(comment 1 "Bryce Canyon / footprints 1371-1379 of 1561")
	)
	(layers
		(0 "F.Cu" signal "TOP")
		(4 "In1.Cu" signal "L2GND")
		(6 "In2.Cu" signal "L3")
		(8 "In3.Cu" signal "L4VCC")
		(10 "In4.Cu" signal "L5VCC")
		(12 "In5.Cu" signal "L6")
		(14 "In6.Cu" signal "L7GND")
		(2 "B.Cu" signal "BOTTOM")
		(9 "F.Adhes" user "F.Adhesive")
		(11 "B.Adhes" user "B.Adhesive")
		(13 "F.Paste" user "Package Geometry/Pastemask Top")
		(15 "B.Paste" user "Package Geometry/Pastemask Bottom")
		(5 "F.SilkS" user "Ref Des/Silkscreen Top")
		(7 "B.SilkS" user "Ref Des/Silkscreen Bottom")
		(1 "F.Mask" user "Board Geometry/Soldermask Top")
		(3 "B.Mask" user "Board Geometry/Soldermask Bottom")
		(17 "Dwgs.User" user "User.Drawings")
		(19 "Cmts.User" user "User.Comments")
		(21 "Eco1.User" user "User.Eco1")
		(23 "Eco2.User" user "User.Eco2")
		(25 "Edge.Cuts" user "Board Geometry/Outline")
		(27 "Margin" user)
		(31 "F.CrtYd" user "Package Geometry/Place Bound Top")
		(29 "B.CrtYd" user "Package Geometry/Place Bound Bottom")
		(35 "F.Fab" user "Ref Des/Assembly Top")
		(33 "B.Fab" user "Ref Des/Assembly Bottom")
	)
	(footprint ""
		(layer "B.Cu")
		(at 122.474228 -67.35953 -90)
		(property "Reference" "C587"
			(at 0 0 90)
			(layer "B.SilkS")
			(hide yes)
			(effects
				(font
					(size 1.27 1.27)
				)
				(justify mirror)
			)
		)
		(property "Value" "SCD1U6D3V1KX-GP"
			(at 2.8321 -1.7399 270)
			(unlocked yes)
			(layer "B.Fab")
			(hide yes)
			(effects
				(font
					(size 1.016 1.016)
					(thickness 0.1524)
				)
				(justify mirror)
			)
		)
		(property "Device Type" "C0201H13"
			(at 2.8321 -3.2639 270)
			(unlocked yes)
			(layer "B.Fab")
			(hide yes)
			(effects
				(font
					(size 1.016 1.016)
					(thickness 0.1524)
				)
				(justify mirror)
			)
		)
		(duplicate_pad_numbers_are_jumpers no)
		(fp_rect
			(start 0.2794 0.6477)
			(end -0.2794 -0.6477)
			(stroke
				(width 0)
				(type default)
			)
			(fill no)
			(layer "B.CrtYd")
		)
		(fp_rect
			(start 0.2794 0.6477)
			(end -0.2794 -0.6477)
			(stroke
				(width 0)
				(type default)
			)
			(fill no)
			(layer "B.Fab")
		)
		(pad "1" smd custom
			(at 0 -0.2794 90)
			(size 0.0762 0.0762)
			(layers "B.Cu" "B.Mask" "B.Paste")
			(net "GB_VDDA")
			(options
				(clearance outline)
				(anchor circle)
			)
			(primitives
				(gr_poly
					(pts
						(arc
							(start 0.1524 0.127)
							(mid 0.137521 0.162921)
							(end 0.1016 0.1778)
						)
						(arc
							(start -0.1016 0.1778)
							(mid -0.137521 0.162921)
							(end -0.1524 0.127)
						)
						(arc
							(start -0.1524 -0.127)
							(mid -0.137521 -0.162921)
							(end -0.1016 -0.1778)
						)
						(arc
							(start 0.1016 -0.1778)
							(mid 0.137521 -0.162921)
							(end 0.1524 -0.127)
						)
					)
					(width 0)
					(fill yes)
				)
			)
		)
		(pad "2" smd custom
			(at 0 0.2794 90)
			(size 0.0762 0.0762)
			(layers "B.Cu" "B.Mask" "B.Paste")
			(net "GND")
			(options
				(clearance outline)
				(anchor circle)
			)
			(primitives
				(gr_poly
					(pts
						(arc
							(start 0.1524 0.127)
							(mid 0.137521 0.162921)
							(end 0.1016 0.1778)
						)
						(arc
							(start -0.1016 0.1778)
							(mid -0.137521 0.162921)
							(end -0.1524 0.127)
						)
						(arc
							(start -0.1524 -0.127)
							(mid -0.137521 -0.162921)
							(end -0.1016 -0.1778)
						)
						(arc
							(start 0.1016 -0.1778)
							(mid 0.137521 -0.162921)
							(end 0.1524 -0.127)
						)
					)
					(width 0)
					(fill yes)
				)
			)
		)
	)
	(footprint ""
		(layer "B.Cu")
		(at 161.798 -50.419)
		(property "Reference" "TP92"
			(at 0 0 0)
			(layer "B.SilkS")
			(hide yes)
			(effects
				(font
					(size 1.27 1.27)
				)
				(justify mirror)
			)
		)
		(property "Value" "TPAD28-2-GP"
			(at 0.0127 -1.6637 0)
			(unlocked yes)
			(layer "B.Fab")
			(hide yes)
			(effects
				(font
					(size 1.016 1.016)
					(thickness 0.1524)
				)
				(justify mirror)
			)
		)
		(property "Device Type" "TPAD28"
			(at 0.0127 -3.1877 0)
			(unlocked yes)
			(layer "B.Fab")
			(hide yes)
			(effects
				(font
					(size 1.016 1.016)
					(thickness 0.1524)
				)
				(justify mirror)
			)
		)
		(duplicate_pad_numbers_are_jumpers no)
		(fp_poly
			(pts
				(arc
					(start 0.3556 0)
					(mid -0.3556 0)
					(end 0.3556 0)
				)
			)
			(stroke
				(width 0)
				(type default)
			)
			(fill no)
			(layer "B.CrtYd")
		)
		(fp_poly
			(pts
				(arc
					(start 0.6096 0)
					(mid -0.6096 0)
					(end 0.6096 0)
				)
			)
			(stroke
				(width 0)
				(type default)
			)
			(fill no)
			(layer "B.Fab")
		)
		(pad "1" smd circle
			(at 0 0 180)
			(size 0.7112 0.7112)
			(layers "B.Cu" "B.Mask" "B.Paste")
			(net "SIO_DOUT_1")
		)
	)
	(footprint ""
		(layer "B.Cu")
		(at 187.5028 -29.8704 90)
		(property "Reference" "TP78"
			(at 0 0 90)
			(layer "B.SilkS")
			(hide yes)
			(effects
				(font
					(size 1.27 1.27)
				)
				(justify mirror)
			)
		)
		(property "Value" "TPAD28-2-GP"
			(at 0.0127 -1.6637 90)
			(unlocked yes)
			(layer "B.Fab")
			(hide yes)
			(effects
				(font
					(size 1.016 1.016)
					(thickness 0.1524)
				)
				(justify mirror)
			)
		)
		(property "Device Type" "TPAD28"
			(at 0.0127 -3.1877 90)
			(unlocked yes)
			(layer "B.Fab")
			(hide yes)
			(effects
				(font
					(size 1.016 1.016)
					(thickness 0.1524)
				)
				(justify mirror)
			)
		)
		(duplicate_pad_numbers_are_jumpers no)
		(fp_poly
			(pts
				(arc
					(start 0 0.3556)
					(mid 0 -0.3556)
					(end 0 0.3556)
				)
			)
			(stroke
				(width 0)
				(type default)
			)
			(fill no)
			(layer "B.CrtYd")
		)
		(fp_poly
			(pts
				(arc
					(start 0 0.6096)
					(mid 0 -0.6096)
					(end 0 0.6096)
				)
			)
			(stroke
				(width 0)
				(type default)
			)
			(fill no)
			(layer "B.Fab")
		)
		(pad "1" smd circle
			(at 0 0 270)
			(size 0.7112 0.7112)
			(layers "B.Cu" "B.Mask" "B.Paste")
			(net "IOC_GPIO_25")
		)
	)
	(footprint ""
		(layer "B.Cu")
		(at 157.867604 -62.090808 90)
		(property "Reference" "C360"
			(at 0 0 90)
			(layer "B.SilkS")
			(hide yes)
			(effects
				(font
					(size 1.27 1.27)
				)
				(justify mirror)
			)
		)
		(property "Value" "SC10U6D3V5KX-4GP"
			(at 0.0762 -6.1214 90)
			(unlocked yes)
			(layer "B.Fab")
			(hide yes)
			(effects
				(font
					(size 1.016 1.016)
					(thickness 0.1524)
				)
				(justify mirror)
			)
		)
		(property "Device Type" "C805H58"
			(at 0.0762 -8.1534 90)
			(unlocked yes)
			(layer "B.Fab")
			(hide yes)
			(effects
				(font
					(size 1.016 1.016)
					(thickness 0.1524)
				)
				(justify mirror)
			)
		)
		(duplicate_pad_numbers_are_jumpers no)
		(fp_line
			(start -0.635 0)
			(end 0.635 0)
			(stroke
				(width 0.508)
				(type default)
			)
			(layer "B.SilkS")
		)
		(fp_rect
			(start 0.9652 1.778)
			(end -0.9652 -1.778)
			(stroke
				(width 0)
				(type default)
			)
			(fill no)
			(layer "B.CrtYd")
		)
		(fp_poly
			(pts
				(xy 0.9652 -1.778) (xy -0.9652 -1.778) (xy -0.9652 1.778) (xy 0.9652 1.778)
			)
			(stroke
				(width 0)
				(type default)
			)
			(fill no)
			(layer "B.Fab")
		)
		(pad "1" smd rect
			(at 0 -0.9652 270)
			(size 1.397 1.143)
			(layers "B.Cu" "B.Mask" "B.Paste")
			(net "SHELL_PLL_VDD")
		)
		(pad "2" smd rect
			(at 0 0.9652 270)
			(size 1.397 1.143)
			(layers "B.Cu" "B.Mask" "B.Paste")
			(net "GND")
		)
	)
	(footprint ""
		(layer "B.Cu")
		(at 62.1792 -54.7878 -90)
		(property "Reference" "C685"
			(at 0 0 90)
			(layer "B.SilkS")
			(hide yes)
			(effects
				(font
					(size 1.27 1.27)
				)
				(justify mirror)
			)
		)
		(property "Value" "SC10U6D3V5KX-4GP"
			(at 0.0762 -6.1214 270)
			(unlocked yes)
			(layer "B.Fab")
			(hide yes)
			(effects
				(font
					(size 1.016 1.016)
					(thickness 0.1524)
				)
				(justify mirror)
			)
		)
		(property "Device Type" "C805H58"
			(at 0.0762 -8.1534 270)
			(unlocked yes)
			(layer "B.Fab")
			(hide yes)
			(effects
				(font
					(size 1.016 1.016)
					(thickness 0.1524)
				)
				(justify mirror)
			)
		)
		(duplicate_pad_numbers_are_jumpers no)
		(fp_line
			(start -0.635 0)
			(end 0.635 0)
			(stroke
				(width 0.508)
				(type default)
			)
			(layer "B.SilkS")
		)
		(fp_rect
			(start 0.9652 1.778)
			(end -0.9652 -1.778)
			(stroke
				(width 0)
				(type default)
			)
			(fill no)
			(layer "B.CrtYd")
		)
		(fp_poly
			(pts
				(xy 0.9652 -1.778) (xy -0.9652 -1.778) (xy -0.9652 1.778) (xy 0.9652 1.778)
			)
			(stroke
				(width 0)
				(type default)
			)
			(fill no)
			(layer "B.Fab")
		)
		(pad "1" smd rect
			(at 0 -0.9652 90)
			(size 1.397 1.143)
			(layers "B.Cu" "B.Mask" "B.Paste")
			(net "P0V9")
		)
		(pad "2" smd rect
			(at 0 0.9652 90)
			(size 1.397 1.143)
			(layers "B.Cu" "B.Mask" "B.Paste")
			(net "GND")
		)
	)
	(footprint ""
		(layer "B.Cu")
		(at 108.839 -44.2214 180)
		(property "Reference" "C73"
			(at 0 0 0)
			(layer "B.SilkS")
			(hide yes)
			(effects
				(font
					(size 1.27 1.27)
				)
				(justify mirror)
			)
		)
		(property "Value" "SCD01U16V1KX-GP"
			(at 2.8321 -1.7399 180)
			(unlocked yes)
			(layer "B.Fab")
			(hide yes)
			(effects
				(font
					(size 1.016 1.016)
					(thickness 0.1524)
				)
				(justify mirror)
			)
		)
		(property "Device Type" "C0201H13"
			(at 2.8321 -3.2639 180)
			(unlocked yes)
			(layer "B.Fab")
			(hide yes)
			(effects
				(font
					(size 1.016 1.016)
					(thickness 0.1524)
				)
				(justify mirror)
			)
		)
		(duplicate_pad_numbers_are_jumpers no)
		(fp_rect
			(start 0.2794 0.6477)
			(end -0.2794 -0.6477)
			(stroke
				(width 0)
				(type default)
			)
			(fill no)
			(layer "B.CrtYd")
		)
		(fp_rect
			(start 0.2794 0.6477)
			(end -0.2794 -0.6477)
			(stroke
				(width 0)
				(type default)
			)
			(fill no)
			(layer "B.Fab")
		)
		(pad "1" smd custom
			(at 0 -0.2794)
			(size 0.0762 0.0762)
			(layers "B.Cu" "B.Mask" "B.Paste")
			(net "PHY_DPB_TO_SCC_24_DN")
			(options
				(clearance outline)
				(anchor circle)
			)
			(primitives
				(gr_poly
					(pts
						(arc
							(start 0.1524 0.127)
							(mid 0.137521 0.162921)
							(end 0.1016 0.1778)
						)
						(arc
							(start -0.1016 0.1778)
							(mid -0.137521 0.162921)
							(end -0.1524 0.127)
						)
						(arc
							(start -0.1524 -0.127)
							(mid -0.137521 -0.162921)
							(end -0.1016 -0.1778)
						)
						(arc
							(start 0.1016 -0.1778)
							(mid 0.137521 -0.162921)
							(end 0.1524 -0.127)
						)
					)
					(width 0)
					(fill yes)
				)
			)
		)
		(pad "2" smd custom
			(at 0 0.2794)
			(size 0.0762 0.0762)
			(layers "B.Cu" "B.Mask" "B.Paste")
			(net "PHY_DPB_TO_SCC_C_24_DN")
			(options
				(clearance outline)
				(anchor circle)
			)
			(primitives
				(gr_poly
					(pts
						(arc
							(start 0.1524 0.127)
							(mid 0.137521 0.162921)
							(end 0.1016 0.1778)
						)
						(arc
							(start -0.1016 0.1778)
							(mid -0.137521 0.162921)
							(end -0.1524 0.127)
						)
						(arc
							(start -0.1524 -0.127)
							(mid -0.137521 -0.162921)
							(end -0.1016 -0.1778)
						)
						(arc
							(start 0.1016 -0.1778)
							(mid 0.137521 -0.162921)
							(end 0.1524 -0.127)
						)
					)
					(width 0)
					(fill yes)
				)
			)
		)
	)
	(footprint ""
		(layer "B.Cu")
		(at 72.517 -14.558772 180)
		(property "Reference" "C97"
			(at 0 0 0)
			(layer "B.SilkS")
			(hide yes)
			(effects
				(font
					(size 1.27 1.27)
				)
				(justify mirror)
			)
		)
		(property "Value" "SCD1U16V2KX-3GP"
			(at -1.1811 -2.7051 180)
			(unlocked yes)
			(layer "B.Fab")
			(hide yes)
			(effects
				(font
					(size 1.016 1.016)
					(thickness 0.1524)
				)
				(justify mirror)
			)
		)
		(property "Device Type" "C402H22"
			(at -1.1811 -4.2291 180)
			(unlocked yes)
			(layer "B.Fab")
			(hide yes)
			(effects
				(font
					(size 1.016 1.016)
					(thickness 0.1524)
				)
				(justify mirror)
			)
		)
		(duplicate_pad_numbers_are_jumpers no)
		(fp_rect
			(start 0.4318 0.9525)
			(end -0.4318 -0.9525)
			(stroke
				(width 0)
				(type default)
			)
			(fill no)
			(layer "B.CrtYd")
		)
		(fp_rect
			(start 0.4318 0.9525)
			(end -0.4318 -0.9525)
			(stroke
				(width 0)
				(type default)
			)
			(fill no)
			(layer "B.Fab")
		)
		(pad "1" smd custom
			(at 0 -0.4445)
			(size 0.1524 0.1524)
			(layers "B.Cu" "B.Mask" "B.Paste")
			(net "P3V3")
			(options
				(clearance outline)
				(anchor circle)
			)
			(primitives
				(gr_poly
					(pts
						(arc
							(start 0.3048 0.2032)
							(mid 0.275042 0.275042)
							(end 0.2032 0.3048)
						)
						(arc
							(start -0.2032 0.3048)
							(mid -0.275042 0.275042)
							(end -0.3048 0.2032)
						)
						(arc
							(start -0.3048 -0.2032)
							(mid -0.275042 -0.275042)
							(end -0.2032 -0.3048)
						)
						(arc
							(start 0.2032 -0.3048)
							(mid 0.275042 -0.275042)
							(end 0.3048 -0.2032)
						)
					)
					(width 0)
					(fill yes)
				)
			)
		)
		(pad "2" smd custom
			(at 0 0.4445)
			(size 0.1524 0.1524)
			(layers "B.Cu" "B.Mask" "B.Paste")
			(net "GND")
			(options
				(clearance outline)
				(anchor circle)
			)
			(primitives
				(gr_poly
					(pts
						(arc
							(start 0.3048 0.2032)
							(mid 0.275042 0.275042)
							(end 0.2032 0.3048)
						)
						(arc
							(start -0.2032 0.3048)
							(mid -0.275042 0.275042)
							(end -0.3048 0.2032)
						)
						(arc
							(start -0.3048 -0.2032)
							(mid -0.275042 -0.275042)
							(end -0.2032 -0.3048)
						)
						(arc
							(start 0.2032 -0.3048)
							(mid 0.275042 -0.275042)
							(end 0.3048 -0.2032)
						)
					)
					(width 0)
					(fill yes)
				)
			)
		)
	)
	(footprint ""
		(layer "B.Cu")
		(at 142.01267 -119.51716 90)
		(property "Reference" "Q13"
			(at 0 0 90)
			(layer "B.SilkS")
			(hide yes)
			(effects
				(font
					(size 1.27 1.27)
				)
				(justify mirror)
			)
		)
		(property "Value" "2N7002E-2-GP"
			(at -0.127 -8.9662 90)
			(unlocked yes)
			(layer "B.Fab")
			(hide yes)
			(effects
				(font
					(size 1.016 1.016)
					(thickness 0.1524)
				)
				(justify mirror)
			)
		)
		(property "Device Type" "SOT23DGS2D4H44"
			(at -0.127 -10.4902 90)
			(unlocked yes)
			(layer "B.Fab")
			(hide yes)
			(effects
				(font
					(size 1.016 1.016)
					(thickness 0.1524)
				)
				(justify mirror)
			)
		)
		(duplicate_pad_numbers_are_jumpers no)
		(fp_line
			(start 1.651 -1.778)
			(end 1.651 1.778)
			(stroke
				(width 0.1524)
				(type default)
			)
			(layer "B.SilkS")
		)
		(fp_line
			(start -1.651 -1.778)
			(end 1.651 -1.778)
			(stroke
				(width 0.1524)
				(type default)
			)
			(layer "B.SilkS")
		)
		(fp_line
			(start 1.651 1.778)
			(end -1.651 1.778)
			(stroke
				(width 0.1524)
				(type default)
			)
			(layer "B.SilkS")
		)
		(fp_line
			(start -1.651 1.778)
			(end -1.651 -1.778)
			(stroke
				(width 0.1524)
				(type default)
			)
			(layer "B.SilkS")
		)
		(fp_poly
			(pts
				(xy 1.778 1.8796) (xy 1.778 -1.8796) (xy -1.778 -1.8796) (xy -1.778 1.8796)
			)
			(stroke
				(width 0)
				(type default)
			)
			(fill no)
			(layer "B.CrtYd")
		)
		(fp_poly
			(pts
				(xy 1.778 1.8796) (xy 1.778 -1.8796) (xy -1.778 -1.8796) (xy -1.778 1.8796)
			)
			(stroke
				(width 0)
				(type default)
			)
			(fill no)
			(layer "B.Fab")
		)
		(pad "D" smd custom
			(at 0 -0.9525 270)
			(size 0.1905 0.1905)
			(layers "B.Cu" "B.Mask" "B.Paste")
			(net "P1V5_C_PG_G")
			(options
				(clearance outline)
				(anchor circle)
			)
			(primitives
				(gr_poly
					(pts
						(arc
							(start -0.1778 -0.5715)
							(mid -0.321484 -0.511984)
							(end -0.381 -0.3683)
						)
						(arc
							(start -0.381 0.3683)
							(mid -0.321484 0.511984)
							(end -0.1778 0.5715)
						)
						(arc
							(start 0.1778 0.5715)
							(mid 0.321484 0.511984)
							(end 0.381 0.3683)
						)
						(arc
							(start 0.381 -0.3683)
							(mid 0.321484 -0.511984)
							(end 0.1778 -0.5715)
						)
					)
					(width 0)
					(fill yes)
				)
			)
		)
		(pad "G" smd custom
			(at 0.98425 0.9525 270)
			(size 0.1905 0.1905)
			(layers "B.Cu" "B.Mask" "B.Paste")
			(net "P1V8_C_PG_G")
			(options
				(clearance outline)
				(anchor circle)
			)
			(primitives
				(gr_poly
					(pts
						(arc
							(start -0.1778 -0.5715)
							(mid -0.321484 -0.511984)
							(end -0.381 -0.3683)
						)
						(arc
							(start -0.381 0.3683)
							(mid -0.321484 0.511984)
							(end -0.1778 0.5715)
						)
						(arc
							(start 0.1778 0.5715)
							(mid 0.321484 0.511984)
							(end 0.381 0.3683)
						)
						(arc
							(start 0.381 -0.3683)
							(mid 0.321484 -0.511984)
							(end 0.1778 -0.5715)
						)
					)
					(width 0)
					(fill yes)
				)
			)
		)
		(pad "S" smd custom
			(at -0.98425 0.9525 270)
			(size 0.1905 0.1905)
			(layers "B.Cu" "B.Mask" "B.Paste")
			(net "P1V5_C_S")
			(options
				(clearance outline)
				(anchor circle)
			)
			(primitives
				(gr_poly
					(pts
						(arc
							(start -0.1778 -0.5715)
							(mid -0.321484 -0.511984)
							(end -0.381 -0.3683)
						)
						(arc
							(start -0.381 0.3683)
							(mid -0.321484 0.511984)
							(end -0.1778 0.5715)
						)
						(arc
							(start 0.1778 0.5715)
							(mid 0.321484 0.511984)
							(end 0.381 0.3683)
						)
						(arc
							(start 0.381 -0.3683)
							(mid 0.321484 -0.511984)
							(end 0.1778 -0.5715)
						)
					)
					(width 0)
					(fill yes)
				)
			)
		)
	)
	(footprint ""
		(layer "B.Cu")
		(at 161.798762 -16.258286 180)
		(property "Reference" "R313"
			(at 0 0 0)
			(layer "B.SilkS")
			(hide yes)
			(effects
				(font
					(size 1.27 1.27)
				)
				(justify mirror)
			)
		)
		(property "Value" "3K83R2F-GP"
			(at -0.064008 -3.993896 180)
			(unlocked yes)
			(layer "B.Fab")
			(hide yes)
			(effects
				(font
					(size 1.016 1.016)
					(thickness 0.1524)
				)
				(justify mirror)
			)
		)
		(property "Device Type" "R402H16"
			(at -0.064008 -5.517896 180)
			(unlocked yes)
			(layer "B.Fab")
			(hide yes)
			(effects
				(font
					(size 1.016 1.016)
					(thickness 0.1524)
				)
				(justify mirror)
			)
		)
		(duplicate_pad_numbers_are_jumpers no)
		(fp_line
			(start 0.508 -0.9398)
			(end 0.508 0.9398)
			(stroke
				(width 0.1524)
				(type default)
			)
			(layer "B.SilkS")
		)
		(fp_line
			(start -0.508 -0.9398)
			(end 0.508 -0.9398)
			(stroke
				(width 0.1524)
				(type default)
			)
			(layer "B.SilkS")
		)
		(fp_rect
			(start 0.508 0.9398)
			(end -0.508 -0.9398)
			(stroke
				(width 0)
				(type default)
			)
			(fill no)
			(layer "B.CrtYd")
		)
		(fp_rect
			(start 0.508 0.9398)
			(end -0.508 -0.9398)
			(stroke
				(width 0)
				(type default)
			)
			(fill no)
			(layer "B.Fab")
		)
		(pad "1" smd custom
			(at 0 -0.4445)
			(size 0.1397 0.1397)
			(layers "B.Cu" "B.Mask" "B.Paste")
			(net "LS_EN_N")
			(options
				(clearance outline)
				(anchor circle)
			)
			(primitives
				(gr_poly
					(pts
						(arc
							(start -0.1778 0.2794)
							(mid -0.249642 0.249642)
							(end -0.2794 0.1778)
						)
						(arc
							(start -0.2794 -0.1778)
							(mid -0.249642 -0.249642)
							(end -0.1778 -0.2794)
						)
						(arc
							(start 0.1778 -0.2794)
							(mid 0.249642 -0.249642)
							(end 0.2794 -0.1778)
						)
						(arc
							(start 0.2794 0.1778)
							(mid 0.249642 0.249642)
							(end 0.1778 0.2794)
						)
					)
					(width 0)
					(fill yes)
				)
			)
		)
		(pad "2" smd custom
			(at 0 0.4445)
			(size 0.1397 0.1397)
			(layers "B.Cu" "B.Mask" "B.Paste")
			(net "GND")
			(options
				(clearance outline)
				(anchor circle)
			)
			(primitives
				(gr_poly
					(pts
						(arc
							(start -0.1778 0.2794)
							(mid -0.249642 0.249642)
							(end -0.2794 0.1778)
						)
						(arc
							(start -0.2794 -0.1778)
							(mid -0.249642 -0.249642)
							(end -0.1778 -0.2794)
						)
						(arc
							(start 0.1778 -0.2794)
							(mid 0.249642 -0.249642)
							(end 0.2794 -0.1778)
						)
						(arc
							(start 0.2794 0.1778)
							(mid 0.249642 0.249642)
							(end 0.1778 0.2794)
						)
					)
					(width 0)
					(fill yes)
				)
			)
		)
	)
)
